G04 ================== begin FILE IDENTIFICATION RECORD ==================*
G04 Layout Name:  9049_F0T_FAN_BOARD_MP5048_D_v02_20221209_0830.brd*
G04 Film Name:    outline*
G04 File Format:  Gerber RS274X*
G04 File Origin:  Cadence Allegro 17.2-S081*
G04 Origin Date:  Mon Dec 12 15:05:05 2022*
G04 *
G04 Layer:  BOARD GEOMETRY/DESIGN_OUTLINE*
G04 Layer:  BOARD GEOMETRY/CUTOUT*
G04 *
G04 Offset:    (0.00 0.00)*
G04 Mirror:    No*
G04 Mode:      Positive*
G04 Rotation:  0*
G04 FullContactRelief:  No*
G04 UndefLineWidth:     6.00*
G04 ================== end FILE IDENTIFICATION RECORD ====================*
%FSLAX25Y25*MOIN*%
%IR0*IPPOS*OFA0.00000B0.00000*MIA0B0*SFA1.00000B1.00000*%
%ADD10C,.006*%
G75*
%LPD*%
G75*
G54D10*
G01X138740Y5906D02*
X144646Y0D01*
X187795D01*
G03X203543Y15748I0J15748D01*
G01Y1311024D01*
G03X187795Y1326772I-15748J0D01*
G01X15748D01*
G03X0Y1311024I0J-15748D01*
G01Y15748D01*
G03X15748Y0I15748J0D01*
G01X58898D01*
X64803Y5906D01*
Y43307D01*
G02X74252I4724J0D01*
G01Y7283D01*
X80157Y1378D01*
X99488D01*
X105394Y7283D01*
Y43307D01*
G02X108150I1378J0D01*
G01Y7283D01*
X114055Y1378D01*
X123386D01*
X129291Y7283D01*
Y43307D01*
G02X138740I4724J0D01*
G01Y5906D01*
G01X27362Y41378D02*
G02X33268I2953J0D01*
G02X27362I-2953J0D01*
G01Y404764D02*
G02X33268I2953J0D01*
G02X27362I-2953J0D01*
G01Y768150D02*
G02X33268I2953J0D01*
G02X27362I-2953J0D01*
G01Y1131535D02*
G02X33268I2953J0D01*
G02X27362I-2953J0D01*
G01X32908Y574289D02*
X36832Y621205D01*
G02X48601I5885J-492D01*
G01X52525Y574289D01*
G02X32908I-9808J-820D01*
G01X91929Y157126D02*
X95886Y204858D01*
G02X107657I5886J-488D01*
G01X111614Y157126D01*
G02X91929I-9842J0D01*
G01Y905157D02*
X95886Y952889D01*
G02X107657I5886J-488D01*
G01X111614Y905157D01*
G02X91929I-9842J0D01*
G01X89173Y1287047D02*
G02X114370I12599J0D01*
G02X89173I-12599J0D01*
G01X151019Y574289D02*
X154942Y621205D01*
G02X166712I5885J-492D01*
G01X170635Y574289D01*
G02X151019I-9808J-820D01*
G01X170276Y111457D02*
G02X176181I2953J0D01*
G02X170276I-2952J0D01*
G01Y474843D02*
G02X176181I2953J0D01*
G02X170276I-2952J0D01*
G01Y838228D02*
G02X176181I2953J0D01*
G02X170276I-2952J0D01*
G01Y1201614D02*
G02X176181I2953J0D01*
G02X170276I-2952J0D01*
M02*
